(kicad_pcb
	(version 20260206)
	(generator "pcbnew")
	(generator_version "10.0")
	(general
		(thickness 1.6)
		(legacy_teardrops no)
	)
	(paper "A4")
	(title_block
		(title "Bryce Canyon_SCC_16316-1_OCP.brd")
		(comment 1 "Bryce Canyon / footprints 234-241 of 1561")
	)
	(layers
		(0 "F.Cu" signal "TOP")
		(4 "In1.Cu" signal "L2GND")
		(6 "In2.Cu" signal "L3")
		(8 "In3.Cu" signal "L4VCC")
		(10 "In4.Cu" signal "L5VCC")
		(12 "In5.Cu" signal "L6")
		(14 "In6.Cu" signal "L7GND")
		(2 "B.Cu" signal "BOTTOM")
		(9 "F.Adhes" user "F.Adhesive")
		(11 "B.Adhes" user "B.Adhesive")
		(13 "F.Paste" user "Package Geometry/Pastemask Top")
		(15 "B.Paste" user "Package Geometry/Pastemask Bottom")
		(5 "F.SilkS" user "Ref Des/Silkscreen Top")
		(7 "B.SilkS" user "Ref Des/Silkscreen Bottom")
		(1 "F.Mask" user "Board Geometry/Soldermask Top")
		(3 "B.Mask" user "Board Geometry/Soldermask Bottom")
		(17 "Dwgs.User" user "User.Drawings")
		(19 "Cmts.User" user "User.Comments")
		(21 "Eco1.User" user "User.Eco1")
		(23 "Eco2.User" user "User.Eco2")
		(25 "Edge.Cuts" user "Board Geometry/Outline")
		(27 "Margin" user)
		(31 "F.CrtYd" user "Package Geometry/Place Bound Top")
		(29 "B.CrtYd" user "Package Geometry/Place Bound Bottom")
		(35 "F.Fab" user "Ref Des/Assembly Top")
		(33 "B.Fab" user "Ref Des/Assembly Bottom")
	)
	(footprint ""
		(layer "F.Cu")
		(at 51.089306 -29.56433 180)
		(property "Reference" "R478"
			(at 0 0 180)
			(layer "F.SilkS")
			(hide yes)
			(effects
				(font
					(size 1.27 1.27)
				)
			)
		)
		(property "Value" "0R2F-1-GP"
			(at 0.064008 -3.993896 180)
			(unlocked yes)
			(layer "F.Fab")
			(hide yes)
			(effects
				(font
					(size 1.016 1.016)
					(thickness 0.1524)
				)
			)
		)
		(property "Device Type" "R402H16"
			(at 0.064008 -5.517896 180)
			(unlocked yes)
			(layer "F.Fab")
			(hide yes)
			(effects
				(font
					(size 1.016 1.016)
					(thickness 0.1524)
				)
			)
		)
		(duplicate_pad_numbers_are_jumpers no)
		(fp_line
			(start 0.508 -0.9398)
			(end -0.508 -0.9398)
			(stroke
				(width 0.1524)
				(type default)
			)
			(layer "F.SilkS")
		)
		(fp_line
			(start -0.508 -0.9398)
			(end -0.508 0.9398)
			(stroke
				(width 0.1524)
				(type default)
			)
			(layer "F.SilkS")
		)
		(fp_rect
			(start -0.508 0.9398)
			(end 0.508 -0.9398)
			(stroke
				(width 0)
				(type default)
			)
			(fill no)
			(layer "F.CrtYd")
		)
		(fp_rect
			(start -0.508 0.9398)
			(end 0.508 -0.9398)
			(stroke
				(width 0)
				(type default)
			)
			(fill no)
			(layer "F.Fab")
		)
		(pad "1" smd custom
			(at 0 -0.4445 180)
			(size 0.1397 0.1397)
			(layers "F.Cu" "F.Mask" "F.Paste")
			(net "P0V9_VFB")
			(options
				(clearance outline)
				(anchor circle)
			)
			(primitives
				(gr_poly
					(pts
						(arc
							(start -0.1778 -0.2794)
							(mid -0.249642 -0.249642)
							(end -0.2794 -0.1778)
						)
						(arc
							(start -0.2794 0.1778)
							(mid -0.249642 0.249642)
							(end -0.1778 0.2794)
						)
						(arc
							(start 0.1778 0.2794)
							(mid 0.249642 0.249642)
							(end 0.2794 0.1778)
						)
						(arc
							(start 0.2794 -0.1778)
							(mid 0.249642 -0.249642)
							(end 0.1778 -0.2794)
						)
					)
					(width 0)
					(fill yes)
				)
			)
		)
		(pad "2" smd custom
			(at 0 0.4445 180)
			(size 0.1397 0.1397)
			(layers "F.Cu" "F.Mask" "F.Paste")
			(net "P0V9")
			(options
				(clearance outline)
				(anchor circle)
			)
			(primitives
				(gr_poly
					(pts
						(arc
							(start -0.1778 -0.2794)
							(mid -0.249642 -0.249642)
							(end -0.2794 -0.1778)
						)
						(arc
							(start -0.2794 0.1778)
							(mid -0.249642 0.249642)
							(end -0.1778 0.2794)
						)
						(arc
							(start 0.1778 0.2794)
							(mid 0.249642 0.249642)
							(end 0.2794 0.1778)
						)
						(arc
							(start 0.2794 -0.1778)
							(mid 0.249642 -0.249642)
							(end 0.1778 -0.2794)
						)
					)
					(width 0)
					(fill yes)
				)
			)
		)
	)
	(footprint ""
		(layer "F.Cu")
		(at 168.159938 -23.568406 90)
		(property "Reference" "VIA2"
			(at 0 0 90)
			(layer "F.SilkS")
			(hide yes)
			(effects
				(font
					(size 1.27 1.27)
				)
			)
		)
		(property "Value" "85OHM-8L-1D6MM-L16L18-GP"
			(at 4.064 0.6096 90)
			(unlocked yes)
			(layer "F.Fab")
			(hide yes)
			(effects
				(font
					(size 1.016 1.016)
					(thickness 0.1524)
				)
			)
		)
		(property "Device Type" "VIA-PCIE-4P-368076"
			(at 4.064 -0.9144 90)
			(unlocked yes)
			(layer "F.Fab")
			(hide yes)
			(effects
				(font
					(size 1.016 1.016)
					(thickness 0.1524)
				)
			)
		)
		(duplicate_pad_numbers_are_jumpers no)
		(fp_rect
			(start -1.8415 0.381)
			(end 1.8415 -0.381)
			(stroke
				(width 0)
				(type default)
			)
			(fill no)
			(layer "F.CrtYd")
		)
		(fp_rect
			(start -1.8415 0.381)
			(end 1.8415 -0.381)
			(stroke
				(width 0)
				(type default)
			)
			(fill no)
			(layer "F.Fab")
		)
		(pad "1" thru_hole circle
			(at -1.4605 0 90)
			(size 0.508 0.508)
			(drill 0.254)
			(layers "*.Cu" "*.Mask")
			(remove_unused_layers no)
			(net "GND")
			(clearance 0.127)
			(thermal_gap 0.127)
		)
		(pad "2" thru_hole circle
			(at -0.4445 0 90)
			(size 0.508 0.508)
			(drill 0.254)
			(layers "*.Cu" "*.Mask")
			(remove_unused_layers no)
			(net "PCIE_COMP_TO_SCC_1_DP")
			(clearance 0.127)
			(thermal_gap 0.127)
		)
		(pad "3" thru_hole circle
			(at 0.4445 0 90)
			(size 0.508 0.508)
			(drill 0.254)
			(layers "*.Cu" "*.Mask")
			(remove_unused_layers no)
			(net "PCIE_COMP_TO_SCC_1_DN")
			(clearance 0.127)
			(thermal_gap 0.127)
		)
		(pad "4" thru_hole circle
			(at 1.4605 0 90)
			(size 0.508 0.508)
			(drill 0.254)
			(layers "*.Cu" "*.Mask")
			(remove_unused_layers no)
			(net "GND")
			(clearance 0.127)
			(thermal_gap 0.127)
		)
	)
	(footprint ""
		(layer "F.Cu")
		(at 16.637 -59.1312 180)
		(property "Reference" "R524"
			(at 0 0 180)
			(layer "F.SilkS")
			(hide yes)
			(effects
				(font
					(size 1.27 1.27)
				)
			)
		)
		(property "Value" "0R2J-2-GP"
			(at 0.064008 -3.993896 180)
			(unlocked yes)
			(layer "F.Fab")
			(hide yes)
			(effects
				(font
					(size 1.016 1.016)
					(thickness 0.1524)
				)
			)
		)
		(property "Device Type" "R402H16"
			(at 0.064008 -5.517896 180)
			(unlocked yes)
			(layer "F.Fab")
			(hide yes)
			(effects
				(font
					(size 1.016 1.016)
					(thickness 0.1524)
				)
			)
		)
		(duplicate_pad_numbers_are_jumpers no)
		(fp_line
			(start 0.508 -0.9398)
			(end -0.508 -0.9398)
			(stroke
				(width 0.1524)
				(type default)
			)
			(layer "F.SilkS")
		)
		(fp_line
			(start -0.508 -0.9398)
			(end -0.508 0.9398)
			(stroke
				(width 0.1524)
				(type default)
			)
			(layer "F.SilkS")
		)
		(fp_rect
			(start -0.508 0.9398)
			(end 0.508 -0.9398)
			(stroke
				(width 0)
				(type default)
			)
			(fill no)
			(layer "F.CrtYd")
		)
		(fp_rect
			(start -0.508 0.9398)
			(end 0.508 -0.9398)
			(stroke
				(width 0)
				(type default)
			)
			(fill no)
			(layer "F.Fab")
		)
		(pad "1" smd custom
			(at 0 -0.4445 180)
			(size 0.1397 0.1397)
			(layers "F.Cu" "F.Mask" "F.Paste")
			(net "MB0_SPISS_PD")
			(options
				(clearance outline)
				(anchor circle)
			)
			(primitives
				(gr_poly
					(pts
						(arc
							(start -0.1778 -0.2794)
							(mid -0.249642 -0.249642)
							(end -0.2794 -0.1778)
						)
						(arc
							(start -0.2794 0.1778)
							(mid -0.249642 0.249642)
							(end -0.1778 0.2794)
						)
						(arc
							(start 0.1778 0.2794)
							(mid 0.249642 0.249642)
							(end 0.2794 0.1778)
						)
						(arc
							(start 0.2794 -0.1778)
							(mid 0.249642 -0.249642)
							(end 0.1778 -0.2794)
						)
					)
					(width 0)
					(fill yes)
				)
			)
		)
		(pad "2" smd custom
			(at 0 0.4445 180)
			(size 0.1397 0.1397)
			(layers "F.Cu" "F.Mask" "F.Paste")
			(net "AGND_CURRENT_MON")
			(options
				(clearance outline)
				(anchor circle)
			)
			(primitives
				(gr_poly
					(pts
						(arc
							(start -0.1778 -0.2794)
							(mid -0.249642 -0.249642)
							(end -0.2794 -0.1778)
						)
						(arc
							(start -0.2794 0.1778)
							(mid -0.249642 0.249642)
							(end -0.1778 0.2794)
						)
						(arc
							(start 0.1778 0.2794)
							(mid 0.249642 0.249642)
							(end 0.2794 0.1778)
						)
						(arc
							(start 0.2794 -0.1778)
							(mid 0.249642 -0.249642)
							(end 0.1778 -0.2794)
						)
					)
					(width 0)
					(fill yes)
				)
			)
		)
	)
	(footprint ""
		(layer "F.Cu")
		(at 73.533 -36.068)
		(property "Reference" "C255"
			(at 0 0 0)
			(layer "F.SilkS")
			(hide yes)
			(effects
				(font
					(size 1.27 1.27)
				)
			)
		)
		(property "Value" "SC100U6D3V6MX-GP"
			(at -0.0762 -5.1308 0)
			(unlocked yes)
			(layer "F.Fab")
			(hide yes)
			(effects
				(font
					(size 1.016 1.016)
					(thickness 0.1524)
				)
			)
		)
		(property "Device Type" "C1206H71"
			(at -0.127 -6.6548 0)
			(unlocked yes)
			(layer "F.Fab")
			(hide yes)
			(effects
				(font
					(size 1.016 1.016)
					(thickness 0.1524)
				)
			)
		)
		(duplicate_pad_numbers_are_jumpers no)
		(fp_line
			(start -1.016 -2.2352)
			(end 1.016 -2.2352)
			(stroke
				(width 0.1524)
				(type default)
			)
			(layer "F.SilkS")
		)
		(fp_line
			(start -1.016 -0.8382)
			(end -1.016 -2.2352)
			(stroke
				(width 0.1524)
				(type default)
			)
			(layer "F.SilkS")
		)
		(fp_line
			(start -1.016 2.2352)
			(end -1.016 0.8382)
			(stroke
				(width 0.1524)
				(type default)
			)
			(layer "F.SilkS")
		)
		(fp_line
			(start 1.016 -2.2352)
			(end 1.016 -0.8382)
			(stroke
				(width 0.1524)
				(type default)
			)
			(layer "F.SilkS")
		)
		(fp_line
			(start 1.016 0.8382)
			(end 1.016 2.2352)
			(stroke
				(width 0.1524)
				(type default)
			)
			(layer "F.SilkS")
		)
		(fp_line
			(start 1.016 2.2352)
			(end -1.016 2.2352)
			(stroke
				(width 0.1524)
				(type default)
			)
			(layer "F.SilkS")
		)
		(fp_rect
			(start -1.0922 2.3114)
			(end 1.0922 -2.3114)
			(stroke
				(width 0)
				(type default)
			)
			(fill no)
			(layer "F.CrtYd")
		)
		(fp_poly
			(pts
				(xy 1.0922 -2.3114) (xy 1.0922 2.3114) (xy -1.0922 2.3114) (xy -1.0922 -2.3114)
			)
			(stroke
				(width 0)
				(type default)
			)
			(fill no)
			(layer "F.Fab")
		)
		(pad "1" smd rect
			(at 0 -1.397)
			(size 1.651 1.27)
			(layers "F.Cu" "F.Mask" "F.Paste")
			(net "GB_VDDA")
		)
		(pad "2" smd rect
			(at 0 1.397)
			(size 1.651 1.27)
			(layers "F.Cu" "F.Mask" "F.Paste")
			(net "GND")
		)
	)
	(footprint ""
		(layer "F.Cu")
		(at 57.5564 -72.6948 180)
		(property "Reference" "R422"
			(at 0 0 180)
			(layer "F.SilkS")
			(hide yes)
			(effects
				(font
					(size 1.27 1.27)
				)
			)
		)
		(property "Value" "1KR2F-3-GP"
			(at 0.064008 -3.993896 180)
			(unlocked yes)
			(layer "F.Fab")
			(hide yes)
			(effects
				(font
					(size 1.016 1.016)
					(thickness 0.1524)
				)
			)
		)
		(property "Device Type" "R402H16"
			(at 0.064008 -5.517896 180)
			(unlocked yes)
			(layer "F.Fab")
			(hide yes)
			(effects
				(font
					(size 1.016 1.016)
					(thickness 0.1524)
				)
			)
		)
		(duplicate_pad_numbers_are_jumpers no)
		(fp_line
			(start 0.508 -0.9398)
			(end -0.508 -0.9398)
			(stroke
				(width 0.1524)
				(type default)
			)
			(layer "F.SilkS")
		)
		(fp_line
			(start -0.508 -0.9398)
			(end -0.508 0.9398)
			(stroke
				(width 0.1524)
				(type default)
			)
			(layer "F.SilkS")
		)
		(fp_rect
			(start -0.508 0.9398)
			(end 0.508 -0.9398)
			(stroke
				(width 0)
				(type default)
			)
			(fill no)
			(layer "F.CrtYd")
		)
		(fp_rect
			(start -0.508 0.9398)
			(end 0.508 -0.9398)
			(stroke
				(width 0)
				(type default)
			)
			(fill no)
			(layer "F.Fab")
		)
		(pad "1" smd custom
			(at 0 -0.4445 180)
			(size 0.1397 0.1397)
			(layers "F.Cu" "F.Mask" "F.Paste")
			(net "P3V3")
			(options
				(clearance outline)
				(anchor circle)
			)
			(primitives
				(gr_poly
					(pts
						(arc
							(start -0.1778 -0.2794)
							(mid -0.249642 -0.249642)
							(end -0.2794 -0.1778)
						)
						(arc
							(start -0.2794 0.1778)
							(mid -0.249642 0.249642)
							(end -0.1778 0.2794)
						)
						(arc
							(start 0.1778 0.2794)
							(mid 0.249642 0.249642)
							(end 0.2794 0.1778)
						)
						(arc
							(start 0.2794 -0.1778)
							(mid 0.249642 -0.249642)
							(end 0.1778 -0.2794)
						)
					)
					(width 0)
					(fill yes)
				)
			)
		)
		(pad "2" smd custom
			(at 0 0.4445 180)
			(size 0.1397 0.1397)
			(layers "F.Cu" "F.Mask" "F.Paste")
			(net "I2C_DRIVE_PWR_SCL4")
			(options
				(clearance outline)
				(anchor circle)
			)
			(primitives
				(gr_poly
					(pts
						(arc
							(start -0.1778 -0.2794)
							(mid -0.249642 -0.249642)
							(end -0.2794 -0.1778)
						)
						(arc
							(start -0.2794 0.1778)
							(mid -0.249642 0.249642)
							(end -0.1778 0.2794)
						)
						(arc
							(start 0.1778 0.2794)
							(mid 0.249642 0.249642)
							(end 0.2794 0.1778)
						)
						(arc
							(start 0.2794 -0.1778)
							(mid 0.249642 -0.249642)
							(end 0.1778 -0.2794)
						)
					)
					(width 0)
					(fill yes)
				)
			)
		)
	)
	(footprint ""
		(layer "F.Cu")
		(at 49.584102 -30.110176 -90)
		(property "Reference" "C615"
			(at 0 0 270)
			(layer "F.SilkS")
			(hide yes)
			(effects
				(font
					(size 1.27 1.27)
				)
			)
		)
		(property "Value" "SC1KP50V2KX-1GP"
			(at 1.1811 -2.7051 270)
			(unlocked yes)
			(layer "F.Fab")
			(hide yes)
			(effects
				(font
					(size 1.016 1.016)
					(thickness 0.1524)
				)
			)
		)
		(property "Device Type" "C402H22"
			(at 1.1811 -4.2291 270)
			(unlocked yes)
			(layer "F.Fab")
			(hide yes)
			(effects
				(font
					(size 1.016 1.016)
					(thickness 0.1524)
				)
			)
		)
		(duplicate_pad_numbers_are_jumpers no)
		(fp_rect
			(start -0.4318 0.9525)
			(end 0.4318 -0.9525)
			(stroke
				(width 0)
				(type default)
			)
			(fill no)
			(layer "F.CrtYd")
		)
		(fp_rect
			(start -0.4318 0.9525)
			(end 0.4318 -0.9525)
			(stroke
				(width 0)
				(type default)
			)
			(fill no)
			(layer "F.Fab")
		)
		(pad "1" smd custom
			(at 0 -0.4445 270)
			(size 0.1524 0.1524)
			(layers "F.Cu" "F.Mask" "F.Paste")
			(net "GND")
			(options
				(clearance outline)
				(anchor circle)
			)
			(primitives
				(gr_poly
					(pts
						(arc
							(start 0.3048 -0.2032)
							(mid 0.275042 -0.275042)
							(end 0.2032 -0.3048)
						)
						(arc
							(start -0.2032 -0.3048)
							(mid -0.275042 -0.275042)
							(end -0.3048 -0.2032)
						)
						(arc
							(start -0.3048 0.2032)
							(mid -0.275042 0.275042)
							(end -0.2032 0.3048)
						)
						(arc
							(start 0.2032 0.3048)
							(mid 0.275042 0.275042)
							(end 0.3048 0.2032)
						)
					)
					(width 0)
					(fill yes)
				)
			)
		)
		(pad "2" smd custom
			(at 0 0.4445 270)
			(size 0.1524 0.1524)
			(layers "F.Cu" "F.Mask" "F.Paste")
			(net "P0V9_VSNS")
			(options
				(clearance outline)
				(anchor circle)
			)
			(primitives
				(gr_poly
					(pts
						(arc
							(start 0.3048 -0.2032)
							(mid 0.275042 -0.275042)
							(end 0.2032 -0.3048)
						)
						(arc
							(start -0.2032 -0.3048)
							(mid -0.275042 -0.275042)
							(end -0.3048 -0.2032)
						)
						(arc
							(start -0.3048 0.2032)
							(mid -0.275042 0.275042)
							(end -0.2032 0.3048)
						)
						(arc
							(start 0.2032 0.3048)
							(mid 0.275042 0.275042)
							(end 0.3048 0.2032)
						)
					)
					(width 0)
					(fill yes)
				)
			)
		)
	)
	(footprint ""
		(layer "F.Cu")
		(at 48.110902 -29.551376 180)
		(property "Reference" "C613"
			(at 0 0 180)
			(layer "F.SilkS")
			(hide yes)
			(effects
				(font
					(size 1.27 1.27)
				)
			)
		)
		(property "Value" "SCD01U25V2KX-3GP"
			(at 1.1811 -2.7051 180)
			(unlocked yes)
			(layer "F.Fab")
			(hide yes)
			(effects
				(font
					(size 1.016 1.016)
					(thickness 0.1524)
				)
			)
		)
		(property "Device Type" "C402H22"
			(at 1.1811 -4.2291 180)
			(unlocked yes)
			(layer "F.Fab")
			(hide yes)
			(effects
				(font
					(size 1.016 1.016)
					(thickness 0.1524)
				)
			)
		)
		(duplicate_pad_numbers_are_jumpers no)
		(fp_rect
			(start -0.4318 0.9525)
			(end 0.4318 -0.9525)
			(stroke
				(width 0)
				(type default)
			)
			(fill no)
			(layer "F.CrtYd")
		)
		(fp_rect
			(start -0.4318 0.9525)
			(end 0.4318 -0.9525)
			(stroke
				(width 0)
				(type default)
			)
			(fill no)
			(layer "F.Fab")
		)
		(pad "1" smd custom
			(at 0 -0.4445 180)
			(size 0.1524 0.1524)
			(layers "F.Cu" "F.Mask" "F.Paste")
			(net "P0V9_VSNS")
			(options
				(clearance outline)
				(anchor circle)
			)
			(primitives
				(gr_poly
					(pts
						(arc
							(start 0.3048 -0.2032)
							(mid 0.275042 -0.275042)
							(end 0.2032 -0.3048)
						)
						(arc
							(start -0.2032 -0.3048)
							(mid -0.275042 -0.275042)
							(end -0.3048 -0.2032)
						)
						(arc
							(start -0.3048 0.2032)
							(mid -0.275042 0.275042)
							(end -0.2032 0.3048)
						)
						(arc
							(start 0.2032 0.3048)
							(mid 0.275042 0.275042)
							(end 0.3048 0.2032)
						)
					)
					(width 0)
					(fill yes)
				)
			)
		)
		(pad "2" smd custom
			(at 0 0.4445 180)
			(size 0.1524 0.1524)
			(layers "F.Cu" "F.Mask" "F.Paste")
			(net "P0V9_COMP")
			(options
				(clearance outline)
				(anchor circle)
			)
			(primitives
				(gr_poly
					(pts
						(arc
							(start 0.3048 -0.2032)
							(mid 0.275042 -0.275042)
							(end 0.2032 -0.3048)
						)
						(arc
							(start -0.2032 -0.3048)
							(mid -0.275042 -0.275042)
							(end -0.3048 -0.2032)
						)
						(arc
							(start -0.3048 0.2032)
							(mid -0.275042 0.275042)
							(end -0.2032 0.3048)
						)
						(arc
							(start 0.2032 0.3048)
							(mid 0.275042 0.275042)
							(end 0.3048 0.2032)
						)
					)
					(width 0)
					(fill yes)
				)
			)
		)
	)
	(footprint ""
		(layer "F.Cu")
		(at 177.8508 -99.822)
		(property "Reference" "R491"
			(at 0 0 0)
			(layer "F.SilkS")
			(hide yes)
			(effects
				(font
					(size 1.27 1.27)
				)
			)
		)
		(property "Value" "221R2F-2-GP"
			(at 0.064008 -3.993896 0)
			(unlocked yes)
			(layer "F.Fab")
			(hide yes)
			(effects
				(font
					(size 1.016 1.016)
					(thickness 0.1524)
				)
			)
		)
		(property "Device Type" "R402H16"
			(at 0.064008 -5.517896 0)
			(unlocked yes)
			(layer "F.Fab")
			(hide yes)
			(effects
				(font
					(size 1.016 1.016)
					(thickness 0.1524)
				)
			)
		)
		(duplicate_pad_numbers_are_jumpers no)
		(fp_line
			(start -0.508 -0.9398)
			(end -0.508 0.9398)
			(stroke
				(width 0.1524)
				(type default)
			)
			(layer "F.SilkS")
		)
		(fp_line
			(start 0.508 -0.9398)
			(end -0.508 -0.9398)
			(stroke
				(width 0.1524)
				(type default)
			)
			(layer "F.SilkS")
		)
		(fp_rect
			(start -0.508 0.9398)
			(end 0.508 -0.9398)
			(stroke
				(width 0)
				(type default)
			)
			(fill no)
			(layer "F.CrtYd")
		)
		(fp_rect
			(start -0.508 0.9398)
			(end 0.508 -0.9398)
			(stroke
				(width 0)
				(type default)
			)
			(fill no)
			(layer "F.Fab")
		)
		(pad "1" smd custom
			(at 0 -0.4445)
			(size 0.1397 0.1397)
			(layers "F.Cu" "F.Mask" "F.Paste")
			(net "VT235_VDES_RCC")
			(options
				(clearance outline)
				(anchor circle)
			)
			(primitives
				(gr_poly
					(pts
						(arc
							(start -0.1778 -0.2794)
							(mid -0.249642 -0.249642)
							(end -0.2794 -0.1778)
						)
						(arc
							(start -0.2794 0.1778)
							(mid -0.249642 0.249642)
							(end -0.1778 0.2794)
						)
						(arc
							(start 0.1778 0.2794)
							(mid 0.249642 0.249642)
							(end 0.2794 0.1778)
						)
						(arc
							(start 0.2794 -0.1778)
							(mid 0.249642 -0.249642)
							(end 0.1778 -0.2794)
						)
					)
					(width 0)
					(fill yes)
				)
			)
		)
		(pad "2" smd custom
			(at 0 0.4445)
			(size 0.1397 0.1397)
			(layers "F.Cu" "F.Mask" "F.Paste")
			(net "GND_SENSE")
			(options
				(clearance outline)
				(anchor circle)
			)
			(primitives
				(gr_poly
					(pts
						(arc
							(start -0.1778 -0.2794)
							(mid -0.249642 -0.249642)
							(end -0.2794 -0.1778)
						)
						(arc
							(start -0.2794 0.1778)
							(mid -0.249642 0.249642)
							(end -0.1778 0.2794)
						)
						(arc
							(start 0.1778 0.2794)
							(mid 0.249642 0.249642)
							(end 0.2794 0.1778)
						)
						(arc
							(start 0.2794 -0.1778)
							(mid 0.249642 -0.249642)
							(end 0.1778 -0.2794)
						)
					)
					(width 0)
					(fill yes)
				)
			)
		)
	)
)
